# T6G (Grand Teton) — schematic netlist excerpt (pin names and nets, part order shuffled) for the footprints in the layout excerpt that follows; sources: Cadence DE-HDL packaged netlist, KiCad conversion of 04192023_DAF0TMB3IC0_F0TG_MB_C_brd_V02_OCP.brd

PC637_3  Q_CAP  22UF 4V 20% X6S  pkg C0805  page 223 : A = PVDDIO_P1 ; B = GND
C3910  Q_CAP  22UF 4V 20% X6S  pkg C0402  page 72 : A = PVDDIO_P1 ; B = GND
C509  Q_CAP  10UF 25V 10% X6S  pkg C0805  page 102 : A = P12V_MEM_CPU1 ; B = GND

(kicad_pcb
	(version 20260206)
	(generator "pcbnew")
	(generator_version "10.0")
	(general
		(thickness 1.6)
		(legacy_teardrops no)
	)
	(paper "A4")
	(title_block
		(title "04192023_DAF0TMB3IC0_F0TG_MB_C_brd_V02_OCP.brd")
		(comment 1 "Grand Teton / footprints 7230-7232 of 8354")
	)
	(layers
		(0 "F.Cu" signal "TOP")
		(4 "In1.Cu" signal "GND")
		(6 "In2.Cu" signal "IN1")
		(8 "In3.Cu" signal "GND1")
		(10 "In4.Cu" signal "IN2")
		(12 "In5.Cu" signal "GND2")
		(14 "In6.Cu" signal "IN3")
		(16 "In7.Cu" signal "GND3")
		(18 "In8.Cu" signal "VCC")
		(20 "In9.Cu" signal "VCC1")
		(22 "In10.Cu" signal "GND4")
		(24 "In11.Cu" signal "IN4")
		(26 "In12.Cu" signal "GND5")
		(28 "In13.Cu" signal "IN5")
		(30 "In14.Cu" signal "GND6")
		(32 "In15.Cu" signal "IN6")
		(34 "In16.Cu" signal "GND7")
		(2 "B.Cu" signal "BOTTOM")
		(9 "F.Adhes" user "F.Adhesive")
		(11 "B.Adhes" user "B.Adhesive")
		(13 "F.Paste" user "Package Geometry/Pastemask Top")
		(15 "B.Paste" user "Package Geometry/Pastemask Bottom")
		(5 "F.SilkS" user "Ref Des/Silkscreen Top")
		(7 "B.SilkS" user "Ref Des/Silkscreen Bottom")
		(1 "F.Mask" user "Board Geometry/Soldermask Top")
		(3 "B.Mask" user "Board Geometry/Soldermask Bottom")
		(17 "Dwgs.User" user "User.Drawings")
		(19 "Cmts.User" user "User.Comments")
		(21 "Eco1.User" user "User.Eco1")
		(23 "Eco2.User" user "User.Eco2")
		(25 "Edge.Cuts" user "Board Geometry/Outline")
		(27 "Margin" user)
		(31 "F.CrtYd" user "Package Geometry/Place Bound Top")
		(29 "B.CrtYd" user "Package Geometry/Place Bound Bottom")
		(35 "F.Fab" user "Ref Des/Assembly Top")
		(33 "B.Fab" user "Ref Des/Assembly Bottom")
	)
	(footprint ""
		(layer "B.Cu")
		(at 105.960164 -259.355336 180)
		(property "Reference" "C3910"
			(at 0 0 0)
			(layer "B.SilkS")
			(hide yes)
			(effects
				(font
					(size 1.27 1.27)
				)
				(justify mirror)
			)
		)
		(property "Value" ""
			(at 0 0 0)
			(layer "B.Fab")
			(effects
				(font
					(size 1.27 1.27)
				)
				(justify mirror)
			)
		)
		(duplicate_pad_numbers_are_jumpers no)
		(fp_line
			(start 0.7874 0.4064)
			(end 0.7874 -0.4064)
			(stroke
				(width 0.1524)
				(type default)
			)
			(layer "B.SilkS")
		)
		(fp_line
			(start 0.7874 -0.4064)
			(end -0.7874 -0.4064)
			(stroke
				(width 0.1524)
				(type default)
			)
			(layer "B.SilkS")
		)
		(fp_line
			(start -0.7874 0.4064)
			(end 0.7874 0.4064)
			(stroke
				(width 0.1524)
				(type default)
			)
			(layer "B.SilkS")
		)
		(fp_line
			(start -0.7874 -0.4064)
			(end -0.7874 0.4064)
			(stroke
				(width 0.1524)
				(type default)
			)
			(layer "B.SilkS")
		)
		(fp_line
			(start 0.67945 0.3048)
			(end 0.67945 -0.305054)
			(stroke
				(width 0.1)
				(type default)
			)
			(layer "B.Fab")
		)
		(fp_line
			(start 0.67945 -0.305054)
			(end 0.12065 -0.305054)
			(stroke
				(width 0.1)
				(type default)
			)
			(layer "B.Fab")
		)
		(fp_line
			(start 0.12065 0.3048)
			(end 0.67945 0.3048)
			(stroke
				(width 0.1)
				(type default)
			)
			(layer "B.Fab")
		)
		(fp_line
			(start 0.12065 0.2794)
			(end 0.12065 0.3048)
			(stroke
				(width 0.1)
				(type default)
			)
			(layer "B.Fab")
		)
		(fp_line
			(start 0.12065 -0.2794)
			(end -0.12065 -0.2794)
			(stroke
				(width 0.1)
				(type default)
			)
			(layer "B.Fab")
		)
		(fp_line
			(start 0.12065 -0.305054)
			(end 0.12065 -0.2794)
			(stroke
				(width 0.1)
				(type default)
			)
			(layer "B.Fab")
		)
		(fp_line
			(start -0.120396 0.3048)
			(end -0.120396 0.2794)
			(stroke
				(width 0.1)
				(type default)
			)
			(layer "B.Fab")
		)
		(fp_line
			(start -0.120396 0.2794)
			(end 0.12065 0.2794)
			(stroke
				(width 0.1)
				(type default)
			)
			(layer "B.Fab")
		)
		(fp_line
			(start -0.12065 -0.2794)
			(end -0.12065 -0.3048)
			(stroke
				(width 0.1)
				(type default)
			)
			(layer "B.Fab")
		)
		(fp_line
			(start -0.12065 -0.3048)
			(end -0.67945 -0.3048)
			(stroke
				(width 0.1)
				(type default)
			)
			(layer "B.Fab")
		)
		(fp_line
			(start -0.67945 0.3048)
			(end -0.120396 0.3048)
			(stroke
				(width 0.1)
				(type default)
			)
			(layer "B.Fab")
		)
		(fp_line
			(start -0.67945 -0.3048)
			(end -0.67945 0.3048)
			(stroke
				(width 0.1)
				(type default)
			)
			(layer "B.Fab")
		)
		(pad "1" smd circle
			(at 0.40005 0)
			(size 0 0)
			(layers "B.Cu" "B.Mask" "B.Paste")
			(net "PVDDIO_P1")
		)
		(pad "2" smd circle
			(at -0.40005 0)
			(size 0 0)
			(layers "B.Cu" "B.Mask" "B.Paste")
			(net "GND")
		)
	)
	(footprint ""
		(layer "B.Cu")
		(at 25.152096 -192.66027 180)
		(property "Reference" "C509"
			(at 0 0 0)
			(layer "B.SilkS")
			(hide yes)
			(effects
				(font
					(size 1.27 1.27)
				)
				(justify mirror)
			)
		)
		(property "Value" ""
			(at 0 0 0)
			(layer "B.Fab")
			(effects
				(font
					(size 1.27 1.27)
				)
				(justify mirror)
			)
		)
		(duplicate_pad_numbers_are_jumpers no)
		(fp_line
			(start 1.524 0.762)
			(end 1.524 -0.762)
			(stroke
				(width 0.1524)
				(type default)
			)
			(layer "B.SilkS")
		)
		(fp_line
			(start 1.524 -0.762)
			(end -1.524 -0.762)
			(stroke
				(width 0.1524)
				(type default)
			)
			(layer "B.SilkS")
		)
		(fp_line
			(start -1.524 0.762)
			(end 1.524 0.762)
			(stroke
				(width 0.1524)
				(type default)
			)
			(layer "B.SilkS")
		)
		(fp_line
			(start -1.524 -0.762)
			(end -1.524 0.762)
			(stroke
				(width 0.1524)
				(type default)
			)
			(layer "B.SilkS")
		)
		(fp_line
			(start 1.1049 0.724916)
			(end -1.1049 0.724916)
			(stroke
				(width 0.1)
				(type default)
			)
			(layer "B.Fab")
		)
		(fp_line
			(start 1.1049 -0.724916)
			(end 1.1049 0.724916)
			(stroke
				(width 0.1)
				(type default)
			)
			(layer "B.Fab")
		)
		(fp_line
			(start -1.1049 0.724916)
			(end -1.1049 -0.724916)
			(stroke
				(width 0.1)
				(type default)
			)
			(layer "B.Fab")
		)
		(fp_line
			(start -1.1049 -0.724916)
			(end 1.1049 -0.724916)
			(stroke
				(width 0.1)
				(type default)
			)
			(layer "B.Fab")
		)
		(pad "1" smd rect
			(at 0.889 0 180)
			(size 1.016 1.27)
			(layers "B.Cu" "B.Mask" "B.Paste")
			(net "P12V_MEM_CPU1")
		)
		(pad "2" smd rect
			(at -0.889 0 180)
			(size 1.016 1.27)
			(layers "B.Cu" "B.Mask" "B.Paste")
			(net "GND")
		)
	)
	(footprint ""
		(layer "B.Cu")
		(at 41.162732 -337.989672 -90)
		(property "Reference" "PC637_3"
			(at 0 0 90)
			(layer "B.SilkS")
			(hide yes)
			(effects
				(font
					(size 1.27 1.27)
				)
				(justify mirror)
			)
		)
		(property "Value" ""
			(at 0 0 90)
			(layer "B.Fab")
			(effects
				(font
					(size 1.27 1.27)
				)
				(justify mirror)
			)
		)
		(duplicate_pad_numbers_are_jumpers no)
		(fp_line
			(start -1.524 0.762)
			(end 1.524 0.762)
			(stroke
				(width 0.1524)
				(type default)
			)
			(layer "B.SilkS")
		)
		(fp_line
			(start 1.524 0.762)
			(end 1.524 -0.762)
			(stroke
				(width 0.1524)
				(type default)
			)
			(layer "B.SilkS")
		)
		(fp_line
			(start -1.524 -0.762)
			(end -1.524 0.762)
			(stroke
				(width 0.1524)
				(type default)
			)
			(layer "B.SilkS")
		)
		(fp_line
			(start 1.524 -0.762)
			(end -1.524 -0.762)
			(stroke
				(width 0.1524)
				(type default)
			)
			(layer "B.SilkS")
		)
		(fp_line
			(start -1.1049 0.724916)
			(end -1.1049 -0.724916)
			(stroke
				(width 0.1)
				(type default)
			)
			(layer "B.Fab")
		)
		(fp_line
			(start 1.1049 0.724916)
			(end -1.1049 0.724916)
			(stroke
				(width 0.1)
				(type default)
			)
			(layer "B.Fab")
		)
		(fp_line
			(start -1.1049 -0.724916)
			(end 1.1049 -0.724916)
			(stroke
				(width 0.1)
				(type default)
			)
			(layer "B.Fab")
		)
		(fp_line
			(start 1.1049 -0.724916)
			(end 1.1049 0.724916)
			(stroke
				(width 0.1)
				(type default)
			)
			(layer "B.Fab")
		)
		(pad "1" smd rect
			(at 0.889 0 270)
			(size 1.016 1.27)
			(layers "B.Cu" "B.Mask" "B.Paste")
			(net "PVDDIO_P1")
		)
		(pad "2" smd rect
			(at -0.889 0 270)
			(size 1.016 1.27)
			(layers "B.Cu" "B.Mask" "B.Paste")
			(net "GND")
		)
	)
)
